(kicad_pcb
	(version 20260206)
	(generator "pcbnew")
	(generator_version "10.0")
	(general
		(thickness 1.6)
		(legacy_teardrops no)
	)
	(paper "A4")
	(title_block
		(title "04192023_DAF0TMB3IC0_F0TG_MB_C_brd_V02_OCP.brd")
		(comment 1 "Grand Teton / footprints 4100-4105 of 8354")
	)
	(layers
		(0 "F.Cu" signal "TOP")
		(4 "In1.Cu" signal "GND")
		(6 "In2.Cu" signal "IN1")
		(8 "In3.Cu" signal "GND1")
		(10 "In4.Cu" signal "IN2")
		(12 "In5.Cu" signal "GND2")
		(14 "In6.Cu" signal "IN3")
		(16 "In7.Cu" signal "GND3")
		(18 "In8.Cu" signal "VCC")
		(20 "In9.Cu" signal "VCC1")
		(22 "In10.Cu" signal "GND4")
		(24 "In11.Cu" signal "IN4")
		(26 "In12.Cu" signal "GND5")
		(28 "In13.Cu" signal "IN5")
		(30 "In14.Cu" signal "GND6")
		(32 "In15.Cu" signal "IN6")
		(34 "In16.Cu" signal "GND7")
		(2 "B.Cu" signal "BOTTOM")
		(9 "F.Adhes" user "F.Adhesive")
		(11 "B.Adhes" user "B.Adhesive")
		(13 "F.Paste" user "Package Geometry/Pastemask Top")
		(15 "B.Paste" user "Package Geometry/Pastemask Bottom")
		(5 "F.SilkS" user "Ref Des/Silkscreen Top")
		(7 "B.SilkS" user "Ref Des/Silkscreen Bottom")
		(1 "F.Mask" user "Board Geometry/Soldermask Top")
		(3 "B.Mask" user "Board Geometry/Soldermask Bottom")
		(17 "Dwgs.User" user "User.Drawings")
		(19 "Cmts.User" user "User.Comments")
		(21 "Eco1.User" user "User.Eco1")
		(23 "Eco2.User" user "User.Eco2")
		(25 "Edge.Cuts" user "Board Geometry/Outline")
		(27 "Margin" user)
		(31 "F.CrtYd" user "Package Geometry/Place Bound Top")
		(29 "B.CrtYd" user "Package Geometry/Place Bound Bottom")
		(35 "F.Fab" user "Ref Des/Assembly Top")
		(33 "B.Fab" user "Ref Des/Assembly Bottom")
	)
	(footprint ""
		(layer "F.Cu")
		(at 12.860274 -390.822434 90)
		(property "Reference" "PC6610"
			(at 0 0 90)
			(layer "F.SilkS")
			(hide yes)
			(effects
				(font
					(size 1.27 1.27)
				)
			)
		)
		(property "Value" ""
			(at 0 0 90)
			(layer "F.Fab")
			(effects
				(font
					(size 1.27 1.27)
				)
			)
		)
		(duplicate_pad_numbers_are_jumpers no)
		(fp_line
			(start 0.7874 -0.4064)
			(end 0.7874 -0.185674)
			(stroke
				(width 0.1524)
				(type default)
			)
			(layer "F.SilkS")
		)
		(fp_line
			(start -0.7874 -0.4064)
			(end 0.7874 -0.4064)
			(stroke
				(width 0.1524)
				(type default)
			)
			(layer "F.SilkS")
		)
		(fp_line
			(start 0.540766 0.4064)
			(end -0.7874 0.4064)
			(stroke
				(width 0.1524)
				(type default)
			)
			(layer "F.SilkS")
		)
		(fp_line
			(start -0.7874 0.4064)
			(end -0.7874 -0.4064)
			(stroke
				(width 0.1524)
				(type default)
			)
			(layer "F.SilkS")
		)
		(fp_line
			(start -0.12065 -0.305054)
			(end -0.12065 -0.2794)
			(stroke
				(width 0.1)
				(type default)
			)
			(layer "F.Fab")
		)
		(fp_line
			(start -0.67945 -0.305054)
			(end -0.12065 -0.305054)
			(stroke
				(width 0.1)
				(type default)
			)
			(layer "F.Fab")
		)
		(fp_line
			(start 0.67945 -0.3048)
			(end 0.67945 0.3048)
			(stroke
				(width 0.1)
				(type default)
			)
			(layer "F.Fab")
		)
		(fp_line
			(start 0.12065 -0.3048)
			(end 0.67945 -0.3048)
			(stroke
				(width 0.1)
				(type default)
			)
			(layer "F.Fab")
		)
		(fp_line
			(start 0.12065 -0.2794)
			(end 0.12065 -0.3048)
			(stroke
				(width 0.1)
				(type default)
			)
			(layer "F.Fab")
		)
		(fp_line
			(start -0.12065 -0.2794)
			(end 0.12065 -0.2794)
			(stroke
				(width 0.1)
				(type default)
			)
			(layer "F.Fab")
		)
		(fp_line
			(start 0.120396 0.2794)
			(end -0.12065 0.2794)
			(stroke
				(width 0.1)
				(type default)
			)
			(layer "F.Fab")
		)
		(fp_line
			(start -0.12065 0.2794)
			(end -0.12065 0.3048)
			(stroke
				(width 0.1)
				(type default)
			)
			(layer "F.Fab")
		)
		(fp_line
			(start 0.67945 0.3048)
			(end 0.120396 0.3048)
			(stroke
				(width 0.1)
				(type default)
			)
			(layer "F.Fab")
		)
		(fp_line
			(start 0.120396 0.3048)
			(end 0.120396 0.2794)
			(stroke
				(width 0.1)
				(type default)
			)
			(layer "F.Fab")
		)
		(fp_line
			(start -0.12065 0.3048)
			(end -0.67945 0.3048)
			(stroke
				(width 0.1)
				(type default)
			)
			(layer "F.Fab")
		)
		(fp_line
			(start -0.67945 0.3048)
			(end -0.67945 -0.305054)
			(stroke
				(width 0.1)
				(type default)
			)
			(layer "F.Fab")
		)
		(pad "1" smd circle
			(at -0.40005 0 90)
			(size 0 0)
			(layers "F.Cu" "F.Mask" "F.Paste")
			(net "P0V9_RETIMER_CPU1_VCC1")
		)
		(pad "2" smd circle
			(at 0.40005 0 90)
			(size 0 0)
			(layers "F.Cu" "F.Mask" "F.Paste")
			(net "GND")
		)
	)
	(footprint ""
		(layer "F.Cu")
		(at 436.100474 -19.62277 -90)
		(property "Reference" "R40"
			(at 0 0 270)
			(layer "F.SilkS")
			(hide yes)
			(effects
				(font
					(size 1.27 1.27)
				)
			)
		)
		(property "Value" ""
			(at 0 0 270)
			(layer "F.Fab")
			(effects
				(font
					(size 1.27 1.27)
				)
			)
		)
		(duplicate_pad_numbers_are_jumpers no)
		(fp_line
			(start -0.7874 0.4064)
			(end -0.7874 -0.4064)
			(stroke
				(width 0.1524)
				(type default)
			)
			(layer "F.SilkS")
		)
		(fp_line
			(start 0.7874 0.4064)
			(end -0.7874 0.4064)
			(stroke
				(width 0.1524)
				(type default)
			)
			(layer "F.SilkS")
		)
		(fp_line
			(start -0.7874 -0.4064)
			(end 0.7874 -0.4064)
			(stroke
				(width 0.1524)
				(type default)
			)
			(layer "F.SilkS")
		)
		(fp_line
			(start 0.7874 -0.4064)
			(end 0.7874 0.4064)
			(stroke
				(width 0.1524)
				(type default)
			)
			(layer "F.SilkS")
		)
		(fp_line
			(start -0.67945 0.3048)
			(end -0.67945 -0.305054)
			(stroke
				(width 0.1)
				(type default)
			)
			(layer "F.Fab")
		)
		(fp_line
			(start -0.12065 0.3048)
			(end -0.67945 0.3048)
			(stroke
				(width 0.1)
				(type default)
			)
			(layer "F.Fab")
		)
		(fp_line
			(start 0.120396 0.3048)
			(end 0.120396 0.2794)
			(stroke
				(width 0.1)
				(type default)
			)
			(layer "F.Fab")
		)
		(fp_line
			(start 0.67945 0.3048)
			(end 0.120396 0.3048)
			(stroke
				(width 0.1)
				(type default)
			)
			(layer "F.Fab")
		)
		(fp_line
			(start -0.12065 0.2794)
			(end -0.12065 0.3048)
			(stroke
				(width 0.1)
				(type default)
			)
			(layer "F.Fab")
		)
		(fp_line
			(start 0.120396 0.2794)
			(end -0.12065 0.2794)
			(stroke
				(width 0.1)
				(type default)
			)
			(layer "F.Fab")
		)
		(fp_line
			(start -0.12065 -0.2794)
			(end 0.12065 -0.2794)
			(stroke
				(width 0.1)
				(type default)
			)
			(layer "F.Fab")
		)
		(fp_line
			(start 0.12065 -0.2794)
			(end 0.12065 -0.3048)
			(stroke
				(width 0.1)
				(type default)
			)
			(layer "F.Fab")
		)
		(fp_line
			(start 0.12065 -0.3048)
			(end 0.67945 -0.3048)
			(stroke
				(width 0.1)
				(type default)
			)
			(layer "F.Fab")
		)
		(fp_line
			(start 0.67945 -0.3048)
			(end 0.67945 0.3048)
			(stroke
				(width 0.1)
				(type default)
			)
			(layer "F.Fab")
		)
		(fp_line
			(start -0.67945 -0.305054)
			(end -0.12065 -0.305054)
			(stroke
				(width 0.1)
				(type default)
			)
			(layer "F.Fab")
		)
		(fp_line
			(start -0.12065 -0.305054)
			(end -0.12065 -0.2794)
			(stroke
				(width 0.1)
				(type default)
			)
			(layer "F.Fab")
		)
		(pad "1" smd circle
			(at -0.40005 0 270)
			(size 0 0)
			(layers "F.Cu" "F.Mask" "F.Paste")
			(net "OCP_SFF_ISO_BIF1_EN")
		)
		(pad "2" smd circle
			(at 0.40005 0 270)
			(size 0 0)
			(layers "F.Cu" "F.Mask" "F.Paste")
			(net "OCP_SFF_BIF1_R_N")
		)
	)
	(footprint ""
		(layer "F.Cu")
		(at 432.24704 -435.436772)
		(property "Reference" "Q70"
			(at -1.4224 -1.768348 0)
			(unlocked yes)
			(layer "F.SilkS")
			(effects
				(font
					(size 0.7874 0.5842)
					(thickness 0.1524)
				)
				(justify left)
			)
		)
		(property "Value" ""
			(at 0 0 0)
			(layer "F.Fab")
			(effects
				(font
					(size 1.27 1.27)
				)
			)
		)
		(duplicate_pad_numbers_are_jumpers no)
		(fp_line
			(start -1.332738 -1.100074)
			(end -0.4826 -1.100074)
			(stroke
				(width 0.1524)
				(type default)
			)
			(layer "F.SilkS")
		)
		(fp_line
			(start -1.332738 1.100074)
			(end -1.332738 -1.100074)
			(stroke
				(width 0.1524)
				(type default)
			)
			(layer "F.SilkS")
		)
		(fp_line
			(start -0.4826 -1.100074)
			(end 0 -0.541274)
			(stroke
				(width 0.1524)
				(type default)
			)
			(layer "F.SilkS")
		)
		(fp_line
			(start 0 -0.541274)
			(end 0.4826 -1.100074)
			(stroke
				(width 0.1524)
				(type default)
			)
			(layer "F.SilkS")
		)
		(fp_line
			(start 0.4826 -1.100074)
			(end 1.332738 -1.100074)
			(stroke
				(width 0.1524)
				(type default)
			)
			(layer "F.SilkS")
		)
		(fp_line
			(start 1.332738 -1.100074)
			(end 1.332738 1.100074)
			(stroke
				(width 0.1524)
				(type default)
			)
			(layer "F.SilkS")
		)
		(fp_line
			(start 1.332738 1.100074)
			(end -1.332738 1.100074)
			(stroke
				(width 0.1524)
				(type default)
			)
			(layer "F.SilkS")
		)
		(fp_poly
			(pts
				(xy -1.630934 -1.2446) (xy -2.356358 -1.544066) (xy -1.826514 -2.004568)
			)
			(stroke
				(width 0)
				(type default)
			)
			(fill yes)
			(layer "F.SilkS")
		)
		(fp_line
			(start -0.674878 -1.100074)
			(end 0.674878 -1.100074)
			(stroke
				(width 0.1)
				(type default)
			)
			(layer "F.Fab")
		)
		(fp_line
			(start -0.674878 1.100074)
			(end -0.674878 -1.100074)
			(stroke
				(width 0.1)
				(type default)
			)
			(layer "F.Fab")
		)
		(fp_line
			(start 0.674878 -1.100074)
			(end 0.674878 1.100074)
			(stroke
				(width 0.1)
				(type default)
			)
			(layer "F.Fab")
		)
		(fp_line
			(start 0.674878 1.100074)
			(end -0.674878 1.100074)
			(stroke
				(width 0.1)
				(type default)
			)
			(layer "F.Fab")
		)
		(fp_poly
			(pts
				(xy -2.2352 -0.298958) (xy -2.2352 -1.001014) (xy -1.533144 -0.649986)
			)
			(stroke
				(width 0)
				(type default)
			)
			(fill yes)
			(layer "F.Fab")
		)
		(pad "1" smd rect
			(at -0.94996 -0.649986 90)
			(size 0.4318 0.508)
			(layers "F.Cu" "F.Mask" "F.Paste")
			(net "GND")
		)
		(pad "2" smd rect
			(at -0.94996 0 90)
			(size 0.4318 0.508)
			(layers "F.Cu" "F.Mask" "F.Paste")
			(net "FM_SWB_BIC_READY_N")
		)
		(pad "3" smd rect
			(at -0.94996 0.649986 90)
			(size 0.4318 0.508)
			(layers "F.Cu" "F.Mask" "F.Paste")
			(net "FM_SWB_BIC_READY_ISO_N")
		)
		(pad "4" smd rect
			(at 0.94996 0.649986 90)
			(size 0.4318 0.508)
			(layers "F.Cu" "F.Mask" "F.Paste")
			(net "GND")
		)
		(pad "5" smd rect
			(at 0.94996 0 90)
			(size 0.4318 0.508)
			(layers "F.Cu" "F.Mask" "F.Paste")
			(net "FM_SWB_BIC_READY")
		)
		(pad "6" smd rect
			(at 0.94996 -0.649986 90)
			(size 0.4318 0.508)
			(layers "F.Cu" "F.Mask" "F.Paste")
			(net "FM_SWB_BIC_READY")
		)
	)
	(footprint ""
		(layer "F.Cu")
		(at 46.08068 -108.585 90)
		(property "Reference" "Q7002"
			(at -1.651 -2.25933 90)
			(unlocked yes)
			(layer "F.SilkS")
			(effects
				(font
					(size 0.7874 0.5842)
					(thickness 0.1524)
				)
				(justify left)
			)
		)
		(property "Value" ""
			(at 0 0 90)
			(layer "F.Fab")
			(effects
				(font
					(size 1.27 1.27)
				)
			)
		)
		(duplicate_pad_numbers_are_jumpers no)
		(fp_line
			(start 1.603248 -1.500124)
			(end 1.603248 1.500124)
			(stroke
				(width 0.1524)
				(type default)
			)
			(layer "F.SilkS")
		)
		(fp_line
			(start -1.603248 -1.500124)
			(end 1.603248 -1.500124)
			(stroke
				(width 0.1524)
				(type default)
			)
			(layer "F.SilkS")
		)
		(fp_line
			(start 1.603248 1.500124)
			(end -1.603248 1.500124)
			(stroke
				(width 0.1524)
				(type default)
			)
			(layer "F.SilkS")
		)
		(fp_line
			(start -1.603248 1.500124)
			(end -1.603248 -1.500124)
			(stroke
				(width 0.1524)
				(type default)
			)
			(layer "F.SilkS")
		)
		(fp_line
			(start 0.700024 -1.500124)
			(end -0.700024 -1.500124)
			(stroke
				(width 0.1)
				(type default)
			)
			(layer "F.Fab")
		)
		(fp_line
			(start -0.700024 -1.500124)
			(end -0.700024 -1.169924)
			(stroke
				(width 0.1)
				(type default)
			)
			(layer "F.Fab")
		)
		(fp_line
			(start -0.700024 -1.169924)
			(end -1.249934 -1.169924)
			(stroke
				(width 0.1)
				(type default)
			)
			(layer "F.Fab")
		)
		(fp_line
			(start -1.249934 -1.169924)
			(end -1.249934 -0.729996)
			(stroke
				(width 0.1)
				(type default)
			)
			(layer "F.Fab")
		)
		(fp_line
			(start -0.6985 -0.729996)
			(end -0.6985 0.729996)
			(stroke
				(width 0.1)
				(type default)
			)
			(layer "F.Fab")
		)
		(fp_line
			(start -1.249934 -0.729996)
			(end -0.6985 -0.729996)
			(stroke
				(width 0.1)
				(type default)
			)
			(layer "F.Fab")
		)
		(fp_line
			(start 1.249934 -0.219964)
			(end 0.700024 -0.219964)
			(stroke
				(width 0.1)
				(type default)
			)
			(layer "F.Fab")
		)
		(fp_line
			(start 0.700024 -0.219964)
			(end 0.700024 -1.500124)
			(stroke
				(width 0.1)
				(type default)
			)
			(layer "F.Fab")
		)
		(fp_line
			(start 1.249934 0.219964)
			(end 1.249934 -0.219964)
			(stroke
				(width 0.1)
				(type default)
			)
			(layer "F.Fab")
		)
		(fp_line
			(start 0.700024 0.219964)
			(end 1.249934 0.219964)
			(stroke
				(width 0.1)
				(type default)
			)
			(layer "F.Fab")
		)
		(fp_line
			(start -0.6985 0.729996)
			(end -1.249934 0.729996)
			(stroke
				(width 0.1)
				(type default)
			)
			(layer "F.Fab")
		)
		(fp_line
			(start -1.249934 0.729996)
			(end -1.249934 1.169924)
			(stroke
				(width 0.1)
				(type default)
			)
			(layer "F.Fab")
		)
		(fp_line
			(start -0.700024 1.169924)
			(end -0.700024 1.500124)
			(stroke
				(width 0.1)
				(type default)
			)
			(layer "F.Fab")
		)
		(fp_line
			(start -1.249934 1.169924)
			(end -0.700024 1.169924)
			(stroke
				(width 0.1)
				(type default)
			)
			(layer "F.Fab")
		)
		(fp_line
			(start 0.700024 1.500124)
			(end 0.700024 0.219964)
			(stroke
				(width 0.1)
				(type default)
			)
			(layer "F.Fab")
		)
		(fp_line
			(start -0.700024 1.500124)
			(end 0.700024 1.500124)
			(stroke
				(width 0.1)
				(type default)
			)
			(layer "F.Fab")
		)
		(fp_rect
			(start -0.700024 1.500124)
			(end 0.700024 -1.500124)
			(stroke
				(width 0)
				(type default)
			)
			(fill no)
			(layer "F.Fab")
		)
		(pad "D" smd rect
			(at 0.999998 0)
			(size 0.8128 0.9144)
			(layers "F.Cu" "F.Mask" "F.Paste")
			(net "P3V3_AUX_DSC_G2")
		)
		(pad "G" smd rect
			(at -0.999998 -0.94996)
			(size 0.8128 0.9144)
			(layers "F.Cu" "F.Mask" "F.Paste")
			(net "P3V3_AUX_DSC_G1")
		)
		(pad "S" smd rect
			(at -0.999998 0.94996)
			(size 0.8128 0.9144)
			(layers "F.Cu" "F.Mask" "F.Paste")
			(net "P3V3_AUX_DSC_S1")
		)
	)
	(footprint ""
		(layer "F.Cu")
		(at 136.962388 -385.09448 180)
		(property "Reference" "R894"
			(at 0 0 180)
			(layer "F.SilkS")
			(hide yes)
			(effects
				(font
					(size 1.27 1.27)
				)
			)
		)
		(property "Value" ""
			(at 0 0 180)
			(layer "F.Fab")
			(effects
				(font
					(size 1.27 1.27)
				)
			)
		)
		(duplicate_pad_numbers_are_jumpers no)
		(fp_line
			(start 0.7874 0.4064)
			(end -0.7874 0.4064)
			(stroke
				(width 0.1524)
				(type default)
			)
			(layer "F.SilkS")
		)
		(fp_line
			(start 0.7874 -0.4064)
			(end 0.7874 0.4064)
			(stroke
				(width 0.1524)
				(type default)
			)
			(layer "F.SilkS")
		)
		(fp_line
			(start -0.7874 0.4064)
			(end -0.7874 -0.4064)
			(stroke
				(width 0.1524)
				(type default)
			)
			(layer "F.SilkS")
		)
		(fp_line
			(start -0.7874 -0.4064)
			(end 0.7874 -0.4064)
			(stroke
				(width 0.1524)
				(type default)
			)
			(layer "F.SilkS")
		)
		(fp_line
			(start 0.67945 0.3048)
			(end 0.120396 0.3048)
			(stroke
				(width 0.1)
				(type default)
			)
			(layer "F.Fab")
		)
		(fp_line
			(start 0.67945 -0.3048)
			(end 0.67945 0.3048)
			(stroke
				(width 0.1)
				(type default)
			)
			(layer "F.Fab")
		)
		(fp_line
			(start 0.12065 -0.2794)
			(end 0.12065 -0.3048)
			(stroke
				(width 0.1)
				(type default)
			)
			(layer "F.Fab")
		)
		(fp_line
			(start 0.12065 -0.3048)
			(end 0.67945 -0.3048)
			(stroke
				(width 0.1)
				(type default)
			)
			(layer "F.Fab")
		)
		(fp_line
			(start 0.120396 0.3048)
			(end 0.120396 0.2794)
			(stroke
				(width 0.1)
				(type default)
			)
			(layer "F.Fab")
		)
		(fp_line
			(start 0.120396 0.2794)
			(end -0.12065 0.2794)
			(stroke
				(width 0.1)
				(type default)
			)
			(layer "F.Fab")
		)
		(fp_line
			(start -0.12065 0.3048)
			(end -0.67945 0.3048)
			(stroke
				(width 0.1)
				(type default)
			)
			(layer "F.Fab")
		)
		(fp_line
			(start -0.12065 0.2794)
			(end -0.12065 0.3048)
			(stroke
				(width 0.1)
				(type default)
			)
			(layer "F.Fab")
		)
		(fp_line
			(start -0.12065 -0.2794)
			(end 0.12065 -0.2794)
			(stroke
				(width 0.1)
				(type default)
			)
			(layer "F.Fab")
		)
		(fp_line
			(start -0.12065 -0.305054)
			(end -0.12065 -0.2794)
			(stroke
				(width 0.1)
				(type default)
			)
			(layer "F.Fab")
		)
		(fp_line
			(start -0.67945 0.3048)
			(end -0.67945 -0.305054)
			(stroke
				(width 0.1)
				(type default)
			)
			(layer "F.Fab")
		)
		(fp_line
			(start -0.67945 -0.305054)
			(end -0.12065 -0.305054)
			(stroke
				(width 0.1)
				(type default)
			)
			(layer "F.Fab")
		)
		(pad "1" smd rect
			(at -0.40005 0)
			(size 0.4572 0.508)
			(layers "F.Cu" "F.Mask" "F.Paste")
			(net "P1V8_CPU1_RT3_1A_1D")
		)
		(pad "2" smd rect
			(at 0.40005 0)
			(size 0.4572 0.508)
			(layers "F.Cu" "F.Mask" "F.Paste")
			(net "P1V8_CPU1_RT3_1A")
		)
	)
	(footprint ""
		(layer "F.Cu")
		(at 69.85 -56.642)
		(property "Reference" "U37"
			(at -3.023108 -2.564384 0)
			(unlocked yes)
			(layer "F.SilkS")
			(effects
				(font
					(size 0.7874 0.5842)
					(thickness 0.1524)
				)
				(justify left)
			)
		)
		(property "Value" ""
			(at 0 0 0)
			(layer "F.Fab")
			(effects
				(font
					(size 1.27 1.27)
				)
			)
		)
		(duplicate_pad_numbers_are_jumpers no)
		(fp_line
			(start -1.4986 -1.100074)
			(end 1.4986 -1.100074)
			(stroke
				(width 0.1524)
				(type default)
			)
			(layer "F.SilkS")
		)
		(fp_line
			(start -1.4986 1.100074)
			(end -1.4986 -1.100074)
			(stroke
				(width 0.1524)
				(type default)
			)
			(layer "F.SilkS")
		)
		(fp_line
			(start 1.4986 -1.100074)
			(end 1.4986 1.100074)
			(stroke
				(width 0.1524)
				(type default)
			)
			(layer "F.SilkS")
		)
		(fp_line
			(start 1.4986 1.100074)
			(end -1.4986 1.100074)
			(stroke
				(width 0.1524)
				(type default)
			)
			(layer "F.SilkS")
		)
		(fp_poly
			(pts
				(xy -2.20472 -0.338328) (xy -2.20472 -0.963168) (xy -1.651 -0.635)
			)
			(stroke
				(width 0)
				(type default)
			)
			(fill yes)
			(layer "F.SilkS")
		)
		(fp_line
			(start -0.67437 -1.100074)
			(end 0.67437 -1.100074)
			(stroke
				(width 0.1)
				(type default)
			)
			(layer "F.Fab")
		)
		(fp_line
			(start -0.67437 1.100074)
			(end -0.67437 -1.100074)
			(stroke
				(width 0.1)
				(type default)
			)
			(layer "F.Fab")
		)
		(fp_line
			(start 0.67437 -1.100074)
			(end 0.67437 1.100074)
			(stroke
				(width 0.1)
				(type default)
			)
			(layer "F.Fab")
		)
		(fp_line
			(start 0.67437 1.100074)
			(end -0.67437 1.100074)
			(stroke
				(width 0.1)
				(type default)
			)
			(layer "F.Fab")
		)
		(fp_poly
			(pts
				(xy -2.20472 -0.338328) (xy -2.20472 -0.963168) (xy -1.651 -0.635)
			)
			(stroke
				(width 0)
				(type default)
			)
			(fill yes)
			(layer "F.Fab")
		)
		(pad "1" smd rect
			(at -0.889 -0.649986)
			(size 1.016 0.381)
			(layers "F.Cu" "F.Mask" "F.Paste")
			(net "HP_LVC3_OCP_V3_2_PWRGD_R1")
		)
		(pad "2" smd rect
			(at -0.889 0)
			(size 1.016 0.381)
			(layers "F.Cu" "F.Mask" "F.Paste")
			(net "FM_OCP_V3_2_AUX_PWR_R_EN")
		)
		(pad "3" smd rect
			(at -0.889 0.649986)
			(size 1.016 0.381)
			(layers "F.Cu" "F.Mask" "F.Paste")
			(net "GND")
		)
		(pad "4" smd rect
			(at 0.889 0.649986)
			(size 1.016 0.381)
			(layers "F.Cu" "F.Mask" "F.Paste")
			(net "OCP_V3_2_AUX_PWR_EN_R2")
		)
		(pad "5" smd rect
			(at 0.889 -0.649986)
			(size 1.016 0.381)
			(layers "F.Cu" "F.Mask" "F.Paste")
			(net "P3V3_AUX")
		)
	)
)
